FILE_TYPE = CONNECTIVITY;
{Allegro Design Entry HDL 17.2-2016 S081 (4005846) 1/11/2022}
"PAGE_NUMBER" = 200;
0"NC";
1"P3V3_9ZXL045_VDDA\g";
2"P3V3_9ZXL045_VDD\g";
3"P3V3_9ZXL045_VDDR\g";
4"P3V3\g";
5"P3V3\g";
6"P3V3_9ZXL045_VDDR\g";
7"P3V3\g";
8"P3V3\g";
9"P3V3_9ZXL045_VDD\g";
10"P3V3_9ZXL045_VDDA\g";
11"P3V3\g";
12"P3V3\g";
13"GND\g";
14"GND\g";
15"GND\g";
16"GND\g";
17"GND\g";
18"GND\g";
19"P3V3_9ZXL045";
20"CLK_9ZXL045_SADR0";
21"SMB_HOST_9ZXL045_3V3AUX_SDA";
22"SMB_HOST_9ZXL045_3V3AUX_SCL";
23"FM_9ZXL045_DEV_EN";
24"CLK_100M_SWB_R_DP";
25"CLK_100M_GPU_1_R_DP";
26"CLK_100M_GPU_1_R_DN";
27"CLK_100M_SWB_R_DN";
28"CLK_9ZXL045_HIBW";
29"CLK_SWB_BUF2_OE_N";
30"CLK_GPU_1_OE_N";
31"CLK_GPU_2_OE_N";
32"TP_CLK_100M_BUF_DIF3_DN";
33"FM_9ZXL045_0_OE_N";
34"FM_9ZXL045_3_OE_N";
35"FM_9ZXL045_1_OE_N";
36"FM_9ZXL045_2_OE_N";
37"TP_CLK_100M_BUF_DIF3_DP";
38"CLK_100M_GPU_2_R_DN";
39"CLK_100M_GPU_2_R_DP";
40"CLK_100M_GPU_SWB_REF_DN";
41"CLK_100M_GPU_SWB_REF_DP";
42"NC_U314_FBOUT_N";
43"NC_U314_NC0";
44"NC_U314_NC1";
45"NC_U314_NC2";
46"NC_U314_NC3";
47"NC_U314_FBOUT";
48"CLK_9ZXL045_HIBW";
49"CLK_9ZXL045_SADR0";
50"FM_PLD_CLKS_DEV_EN";
%"9ZXL0451EKILFT"
"1","(8675,6000)","0","pure_quanta","I1";
;
PART_NUMBER"AL000451003"
VALUE"9ZXL0451EKILFT"
PART_TYPE"SMLF"
MATERIAL"IC"
$LOCATION"U314"
CDS_LMAN_SYM_OUTLINE"-475,725,475,-725"
NEEDS_NO_SIZE"TRUE"
CDS_LIB"pure_quanta"
CDS_LOCATION"U314"
$SEC"1"
CDS_SEC"1";
"VSADR0_TRI"
$PN"5"20;
"NC2"
$PN"17"45;
"NC3"
$PN"30"46;
"VDD0"
$PN"12"2;
"DIF3"
$PN"27"37;
"DIF1"
$PN"19"25;
"EPAD_GND"
$PN"33"17;
"^HIBW_BYPM_LOBW# \B"
$PN"32"28;
"VDD1"
$PN"16"2;
"VDDA"
$PN"31"10;
"NC0"
$PN"10"43;
"DIF3# \B"
$PN"28"32;
"DIF2# \B"
$PN"23"38;
"VOE2# \B"
$PN"24"36;
"DIF2"
$PN"22"39;
"DIF1# \B"
$PN"20"26;
"VOE1# \B"
$PN"18"35;
"DIF0"
$PN"13"24;
"DIF0# \B"
$PN"14"27;
"^CKPWRGD_PD# \B"
$PN"1"23;
"VDD2"
$PN"21"2;
"SMBCLK"
$PN"7"22;
"FBOUT_NC# \B"
$PN"8"42;
"NC1"
$PN"11"44;
"SMBDAT"
$PN"6"21;
"VOE3# \B"
$PN"26"34;
"VOE0# \B"
$PN"15"33;
"FBOUT_NC"
$PN"9"47;
"VDD4"
$PN"29"2;
"VDD3"
$PN"25"2;
"VDDR"
$PN"2"3;
"DIF_IN# \B"
$PN"4"40;
"DIF_IN"
$PN"3"41;
%"Q_CAP"
"1","(6050,7375)","0","pure_quanta","I10";
;
PART_NUMBER"CH6101ME900"
VOLTAGE"6.3V"
PACK_TYPE"C0603"
TOLERANCE"20%"
MATERIAL"X6S"
VALUE"10UF"
$LOCATION"C2332"
CDS_LIB"pure_quanta"
CDS_LOCATION"C2332"
$SEC"1"
CDS_SEC"1";
"B"
$PN"2"13;
"A"
$PN"1"6;
%"Q_RES"
"1","(5650,7525)","0","pure_quanta","I11";
;
PART_NUMBER"CS-1003F900"
PACK_TYPE"0603LF"
TOLERANCE"1%"
MATERIAL"CHIP"
VALUE"1"
WATTAGE"1/10W"
$LOCATION"R4475"
CDS_LIB"pure_quanta"
CDS_LOCATION"R4475"
$SEC"1"
CDS_SEC"1";
"B"
$PN"2"6;
"A"
$PN"1"19;
%"UNIVERSAL_GND"
"1","(6400,7000)","0","logical_power","I12";
;
HDL_POWER"GND"
CDS_LIB"logical_power";
"A"13;
%"Q_CAP"
"1","(8600,7825)","0","pure_quanta","I17";
;
PART_NUMBER"CH6101ME900"
VALUE"10UF"
TOLERANCE"20%"
VOLTAGE"6.3V"
PACK_TYPE"C0603"
MATERIAL"X6S"
$LOCATION"C2328"
CDS_LIB"pure_quanta"
CDS_LOCATION"C2328"
$SEC"1"
CDS_SEC"1";
"B"
$PN"2"18;
"A"
$PN"1"9;
%"UNIVERSAL_GND"
"1","(9975,7475)","0","logical_power","I21";
;
HDL_POWER"GND"
CDS_LIB"logical_power";
"A"18;
%"UNIVERSAL_GND"
"1","(9500,5075)","0","logical_power","I22";
;
HDL_POWER"GND"
CDS_LIB"logical_power";
"A"17;
%"UNIVERSAL_POWER"
"1","(6375,8425)","0","logical_power","I23";
;
HDL_POWER"P3V3_9ZXL045_VDDA"
CDS_LIB"logical_power";
"A"1;
%"UNIVERSAL_POWER"
"1","(6400,7625)","0","logical_power","I24";
;
HDL_POWER"P3V3_9ZXL045_VDDR"
CDS_LIB"logical_power";
"A"6;
%"UNIVERSAL_POWER"
"1","(9975,8175)","0","logical_power","I25";
;
HDL_POWER"P3V3_9ZXL045_VDD"
CDS_LIB"logical_power";
"A"9;
%"UNIVERSAL_POWER"
"1","(7625,8150)","0","logical_power","I26";
;
HDL_POWER"P3V3"
CDS_LIB"logical_power";
"A"11;
%"UNIVERSAL_POWER"
"1","(9625,6900)","0","logical_power","I27";
;
HDL_POWER"P3V3_9ZXL045_VDDA"
CDS_LIB"logical_power";
"A"10;
%"UNIVERSAL_POWER"
"1","(7350,6600)","0","logical_power","I28";
;
HDL_POWER"P3V3_9ZXL045_VDDR"
CDS_LIB"logical_power";
"A"3;
%"UNIVERSAL_POWER"
"1","(7750,6900)","0","logical_power","I29";
;
HDL_POWER"P3V3_9ZXL045_VDD"
CDS_LIB"logical_power";
"A"2;
%"Q_RES"
"2","(7275,4100)","0","pure_quanta","I30";
;
PART_NUMBER"CS24752FB03"
PACK_TYPE"0402LF"
MATERIAL"CHIP"
WATTAGE"1/16W"
TOLERANCE"1%"
VALUE"4.75K"
$LOCATION"R4489"
CDS_LIB"pure_quanta"
CDS_LOCATION"R4489"
$SEC"1"
CDS_SEC"1";
"A"
$PN"1"7;
"B"
$PN"2"49;
%"Q_RES"
"2","(7275,3675)","0","pure_quanta","I31";
;
PART_NUMBER"CS24752FB03"
WATTAGE"1/16W"
TOLERANCE"1%"
VALUE"4.75K"
PACK_TYPE"0402LF"
MATERIAL"EMPTY"
$LOCATION"R4490"
CDS_LIB"pure_quanta"
CDS_LOCATION"R4490"
$SEC"1"
CDS_SEC"1";
"A"
$PN"1"49;
"B"
$PN"2"15;
%"UNIVERSAL_POWER"
"1","(7275,4450)","0","logical_power","I32";
;
HDL_POWER"P3V3"
CDS_LIB"logical_power";
"A"7;
%"UNIVERSAL_GND"
"1","(7275,3425)","0","logical_power","I33";
;
CDS_LIB"logical_power"
HDL_POWER"GND";
"A"15;
%"Q_RES"
"1","(6525,5775)","0","pure_quanta","I39";
;
PART_NUMBER"CS04992FB07"
PACK_TYPE"0402LF"
MATERIAL"CHIP"
WATTAGE"1/16W"
VALUE"49.9"
TOLERANCE"1%"
$LOCATION"R4476"
CDS_LIB"pure_quanta"
CDS_LOCATION"R4476"
$SEC"1"
CDS_SEC"1";
"B"
$PN"2"23;
"A"
$PN"1"50;
%"Q_RES"
"1","(5600,8350)","0","pure_quanta","I4";
;
PART_NUMBER"CS-1003F900"
VALUE"1"
TOLERANCE"1%"
MATERIAL"CHIP"
WATTAGE"1/10W"
PACK_TYPE"0603LF"
$LOCATION"R4493"
CDS_LIB"pure_quanta"
CDS_LOCATION"R4493"
$SEC"1"
CDS_SEC"1";
"B"
$PN"2"1;
"A"
$PN"1"19;
%"Q_RES"
"2","(9275,4100)","0","pure_quanta","I48";
;
PART_NUMBER"CS31002FB08"
VALUE"10K"
PACK_TYPE"0402LF"
MATERIAL"CHIP"
WATTAGE"1/16W"
TOLERANCE"1%"
$LOCATION"R4491"
CDS_LIB"pure_quanta"
CDS_LOCATION"R4491"
$SEC"1"
CDS_SEC"1";
"A"
$PN"1"12;
"B"
$PN"2"48;
%"Q_RES"
"2","(9275,3625)","0","pure_quanta","I49";
;
PART_NUMBER"CS31002FB08"
PACK_TYPE"0402LF"
VALUE"10K"
TOLERANCE"1%"
WATTAGE"1/16W"
MATERIAL"CHIP"
$LOCATION"R4492"
CDS_LIB"pure_quanta"
CDS_LOCATION"R4492"
$SEC"1"
CDS_SEC"1";
"A"
$PN"1"48;
"B"
$PN"2"16;
%"Q_CAP"
"1","(6025,8175)","0","pure_quanta","I5";
;
PART_NUMBER"CH6101ME900"
VOLTAGE"6.3V"
PACK_TYPE"C0603"
MATERIAL"X6S"
TOLERANCE"20%"
VALUE"10UF"
$LOCATION"C2331"
CDS_LIB"pure_quanta"
CDS_LOCATION"C2331"
$SEC"1"
CDS_SEC"1";
"B"
$PN"2"14;
"A"
$PN"1"1;
%"UNIVERSAL_POWER"
"1","(9275,4400)","0","logical_power","I50";
;
HDL_POWER"P3V3"
CDS_LIB"logical_power";
"A"12;
%"UNIVERSAL_GND"
"1","(9275,3375)","0","logical_power","I51";
;
CDS_LIB"logical_power"
HDL_POWER"GND";
"A"16;
%"Q_CAP"
"1","(8950,7825)","0","pure_quanta","I54";
;
PART_NUMBER"CH4104K1B00"
MATERIAL"X7R"
VALUE"0.1UF"
PACK_TYPE"0402"
VOLTAGE"25V"
TOLERANCE"10%"
$LOCATION"C2329"
CDS_LIB"pure_quanta"
CDS_LOCATION"C2329"
$SEC"1"
CDS_SEC"1";
"B"
$PN"2"18;
"A"
$PN"1"9;
%"Q_CAP"
"1","(9200,7825)","0","pure_quanta","I55";
;
PART_NUMBER"CH4104K1B00"
VALUE"0.1UF"
MATERIAL"X7R"
TOLERANCE"10%"
PACK_TYPE"0402"
VOLTAGE"25V"
$LOCATION"C2330"
CDS_LIB"pure_quanta"
CDS_LOCATION"C2330"
$SEC"1"
CDS_SEC"1";
"B"
$PN"2"18;
"A"
$PN"1"9;
%"Q_CAP"
"1","(9450,7825)","0","pure_quanta","I56";
;
PART_NUMBER"CH4104K1B00"
VOLTAGE"25V"
VALUE"0.1UF"
TOLERANCE"10%"
PACK_TYPE"0402"
MATERIAL"X7R"
$LOCATION"C2333"
CDS_LIB"pure_quanta"
CDS_LOCATION"C2333"
$SEC"1"
CDS_SEC"1";
"B"
$PN"2"18;
"A"
$PN"1"9;
%"Q_CAP"
"1","(9700,7825)","0","pure_quanta","I57";
;
PART_NUMBER"CH4104K1B00"
PACK_TYPE"0402"
VOLTAGE"25V"
TOLERANCE"10%"
VALUE"0.1UF"
MATERIAL"X7R"
$LOCATION"C2336"
CDS_LIB"pure_quanta"
CDS_LOCATION"C2336"
$SEC"1"
CDS_SEC"1";
"B"
$PN"2"18;
"A"
$PN"1"9;
%"Q_CAP"
"1","(6375,8175)","0","pure_quanta","I58";
;
PART_NUMBER"CH4104K1B00"
VALUE"0.1UF"
TOLERANCE"10%"
VOLTAGE"25V"
PACK_TYPE"0402"
MATERIAL"X7R"
$LOCATION"C2334"
CDS_LIB"pure_quanta"
CDS_LOCATION"C2334"
$SEC"1"
CDS_SEC"1";
"B"
$PN"2"14;
"A"
$PN"1"1;
%"Q_CAP"
"1","(6400,7375)","0","pure_quanta","I59";
;
PART_NUMBER"CH4104K1B00"
VOLTAGE"25V"
MATERIAL"X7R"
VALUE"0.1UF"
PACK_TYPE"0402"
TOLERANCE"10%"
$LOCATION"C2335"
CDS_LIB"pure_quanta"
CDS_LOCATION"C2335"
$SEC"1"
CDS_SEC"1";
"B"
$PN"2"13;
"A"
$PN"1"6;
%"Q_RES"
"1","(10250,5575)","0","pure_quanta","I69";
;
PART_NUMBER"CS31002FB08"
MATERIAL"CHIP"
TOLERANCE"1%"
VALUE"10K"
$LOCATION"R4494"
PACK_TYPE"0402LF"
WATTAGE"1/16W"
CDS_LIB"pure_quanta"
CDS_LOCATION"R4494"
$SEC"1"
CDS_SEC"1";
"B"
$PN"2"5;
"A"
$PN"1"34;
%"UNIVERSAL_POWER"
"1","(4325,8450)","0","logical_power","I7";
;
HDL_POWER"P3V3"
CDS_LIB"logical_power";
"A"8;
%"UNIVERSAL_POWER"
"1","(12775,5875)","0","logical_power","I70";
;
HDL_POWER"P3V3"
CDS_LIB"logical_power";
"A"5;
%"Q_CAP"
"1","(9975,7825)","0","pure_quanta","I71";
;
PART_NUMBER"CH4104K1B00"
VOLTAGE"25V"
VALUE"0.1UF"
TOLERANCE"10%"
MATERIAL"X7R"
PACK_TYPE"0402"
$LOCATION"C2339"
CDS_LIB"pure_quanta"
CDS_LOCATION"C2339"
$SEC"1"
CDS_SEC"1";
"B"
$PN"2"18;
"A"
$PN"1"9;
%"Q_RES"
"1","(10250,5725)","0","pure_quanta","I74";
;
PART_NUMBER"CS03322FB03"
MATERIAL"CHIP"
TOLERANCE"1%"
VALUE"33.2"
LOCATION"R4477"
CDS_LIB"pure_quanta"
WATTAGE"1/16W"
PACK_TYPE"0402LF"
$SEC"1"
CDS_SEC"1";
"B"
$PN"2"29;
"A"
$PN"1"33;
%"Q_RES"
"1","(10250,5675)","0","pure_quanta","I75";
;
PART_NUMBER"CS03322FB03"
TOLERANCE"1%"
MATERIAL"CHIP"
VALUE"33.2"
LOCATION"R4478"
CDS_LIB"pure_quanta"
WATTAGE"1/16W"
PACK_TYPE"0402LF"
$SEC"1"
CDS_SEC"1";
"B"
$PN"2"30;
"A"
$PN"1"35;
%"Q_RES"
"1","(10250,5625)","0","pure_quanta","I76";
;
PART_NUMBER"CS03322FB03"
TOLERANCE"1%"
MATERIAL"CHIP"
VALUE"33.2"
LOCATION"R4479"
PACK_TYPE"0402LF"
WATTAGE"1/16W"
CDS_LIB"pure_quanta"
$SEC"1"
CDS_SEC"1";
"B"
$PN"2"31;
"A"
$PN"1"36;
%"Q_RES"
"2","(11400,6125)","0","pure_quanta","I77";
;
PART_NUMBER"CS31002FB08"
TOLERANCE"1%"
WATTAGE"1/16W"
VALUE"10K"
MATERIAL"CHIP"
PACK_TYPE"0402LF"
$LOCATION"R4518"
CDS_LIB"pure_quanta"
CDS_LOCATION"R4518"
$SEC"1"
CDS_SEC"1";
"A"
$PN"1"4;
"B"
$PN"2"31;
%"Q_RES"
"2","(11625,6125)","0","pure_quanta","I78";
;
PART_NUMBER"CS31002FB08"
TOLERANCE"1%"
PACK_TYPE"0402LF"
MATERIAL"CHIP"
VALUE"10K"
WATTAGE"1/16W"
$LOCATION"R4519"
CDS_LIB"pure_quanta"
CDS_LOCATION"R4519"
$SEC"1"
CDS_SEC"1";
"A"
$PN"1"4;
"B"
$PN"2"30;
%"Q_RES"
"2","(11825,6125)","0","pure_quanta","I79";
;
PART_NUMBER"CS31002FB08"
TOLERANCE"1%"
WATTAGE"1/16W"
MATERIAL"CHIP"
PACK_TYPE"0402LF"
VALUE"10K"
$LOCATION"R4520"
CDS_LIB"pure_quanta"
CDS_LOCATION"R4520"
$SEC"1"
CDS_SEC"1";
"A"
$PN"1"4;
"B"
$PN"2"29;
%"UNIVERSAL_GND"
"1","(6375,7800)","0","logical_power","I8";
;
CDS_LIB"logical_power"
HDL_POWER"GND";
"A"14;
%"UNIVERSAL_POWER"
"1","(11825,6575)","0","logical_power","I80";
;
HDL_POWER"P3V3"
CDS_LIB"logical_power";
"A"4;
%"Q_INDUCTOR"
"1","(4750,8375)","0","pure_quanta","I81";
;
PART_NUMBER"CX601T05003"
MATERIAL"IND"
PACK_TYPE"SMLF"
VALUE"FCM2012KF-601T/0.5A"
LOCATION"L19"
CDS_LIB"pure_quanta"
NEEDS_NO_SIZE"TRUE"
$SEC"1"
CDS_SEC"1";
"1"
$PN"1"8;
"2"
$PN"2"19;
%"Q_INDUCTOR"
"1","(8075,8050)","0","pure_quanta","I82";
;
PART_NUMBER"CX601T05003"
PACK_TYPE"SMLF"
MATERIAL"IND"
VALUE"FCM2012KF-601T/0.5A"
LOCATION"L20"
NEEDS_NO_SIZE"TRUE"
CDS_LIB"pure_quanta"
$SEC"1"
CDS_SEC"1";
"1"
$PN"1"11;
"2"
$PN"2"9;
END.
